# BASEBOARD_FAB2 (Tioga Pass) — schematic netlist excerpt (pin names and nets, part order shuffled) for the footprints in the layout excerpt that follows; sources: Cadence DE-HDL packaged netlist, KiCad conversion of Wiwynn_Tioga_Pass_MB.brd

R6L11  RES  0.0 5% CHIP  pkg 0402  page 222 : A = P3V3 ; B = VR_PVTT_DEF_BIAS
C8P12  CAP  47UF 4V 20% X6S  pkg 0805  page 76 : A = PVCCIN_CPU1 ; B = GND
C9R6  CAP_A  0.1UF 16V 10% X7R  pkg 0402V  page 195 : A = P12V_PSU ; B = GND

(kicad_pcb
	(version 20260206)
	(generator "pcbnew")
	(generator_version "10.0")
	(general
		(thickness 1.6)
		(legacy_teardrops no)
	)
	(paper "A4")
	(title_block
		(title "Wiwynn_Tioga_Pass_MB.brd")
		(comment 1 "Tioga Pass / footprints 3474-3476 of 4770")
	)
	(layers
		(0 "F.Cu" signal "TOP")
		(4 "In1.Cu" signal "L2GND")
		(6 "In2.Cu" signal "L3")
		(8 "In3.Cu" signal "L4GND")
		(10 "In4.Cu" signal "L5")
		(12 "In5.Cu" signal "L6GND")
		(14 "In6.Cu" signal "L7VCC")
		(16 "In7.Cu" signal "L8VCC")
		(18 "In8.Cu" signal "L9GND")
		(20 "In9.Cu" signal "L10")
		(22 "In10.Cu" signal "L11GND")
		(24 "In11.Cu" signal "L12")
		(26 "In12.Cu" signal "L13GND")
		(2 "B.Cu" signal "BOTTOM")
		(9 "F.Adhes" user "F.Adhesive")
		(11 "B.Adhes" user "B.Adhesive")
		(13 "F.Paste" user "Package Geometry/Pastemask Top")
		(15 "B.Paste" user "Package Geometry/Pastemask Bottom")
		(5 "F.SilkS" user "Ref Des/Silkscreen Top")
		(7 "B.SilkS" user "Ref Des/Silkscreen Bottom")
		(1 "F.Mask" user "Board Geometry/Soldermask Top")
		(3 "B.Mask" user "Board Geometry/Soldermask Bottom")
		(17 "Dwgs.User" user "User.Drawings")
		(19 "Cmts.User" user "User.Comments")
		(21 "Eco1.User" user "User.Eco1")
		(23 "Eco2.User" user "User.Eco2")
		(25 "Edge.Cuts" user "Board Geometry/Outline")
		(27 "Margin" user)
		(31 "F.CrtYd" user "Package Geometry/Place Bound Top")
		(29 "B.CrtYd" user "Package Geometry/Place Bound Bottom")
		(35 "F.Fab" user "Ref Des/Assembly Top")
		(33 "B.Fab" user "Ref Des/Assembly Bottom")
	)
	(footprint ""
		(layer "B.Cu")
		(at 181.864 -145.796 180)
		(property "Reference" "R6L11"
			(at 0 0 0)
			(layer "B.SilkS")
			(hide yes)
			(effects
				(font
					(size 1.27 1.27)
				)
				(justify mirror)
			)
		)
		(property "Value" ""
			(at 0 0 0)
			(layer "B.Fab")
			(effects
				(font
					(size 1.27 1.27)
				)
				(justify mirror)
			)
		)
		(duplicate_pad_numbers_are_jumpers no)
		(fp_rect
			(start -0.2794 0.9906)
			(end 0.2794 -0.1016)
			(stroke
				(width 0)
				(type default)
			)
			(fill no)
			(layer "B.CrtYd")
		)
		(fp_line
			(start 0.2794 0.9906)
			(end -0.2794 0.9906)
			(stroke
				(width 0.1)
				(type default)
			)
			(layer "B.Fab")
		)
		(fp_line
			(start 0.2794 -0.1016)
			(end 0.2794 0.9906)
			(stroke
				(width 0.1)
				(type default)
			)
			(layer "B.Fab")
		)
		(fp_line
			(start -0.2794 0.9906)
			(end -0.2794 -0.1016)
			(stroke
				(width 0.1)
				(type default)
			)
			(layer "B.Fab")
		)
		(fp_line
			(start -0.2794 -0.1016)
			(end 0.2794 -0.1016)
			(stroke
				(width 0.1)
				(type default)
			)
			(layer "B.Fab")
		)
		(pad "1" smd rect
			(at 0 0)
			(size 0.508 0.508)
			(layers "B.Cu" "B.Mask" "B.Paste")
			(net "P3V3")
		)
		(pad "2" smd rect
			(at 0 0.889)
			(size 0.508 0.508)
			(layers "B.Cu" "B.Mask" "B.Paste")
			(net "VR_PVTT_DEF_BIAS")
		)
		(zone
			(layer "B.Cu")
			(hatch none 0.5)
			(connect_pads
				(clearance 0)
			)
			(min_thickness 0.25)
			(keepout
				(tracks not_allowed)
				(vias allowed)
				(pads allowed)
				(copperpour not_allowed)
				(footprints allowed)
			)
			(placement
				(enabled no)
				(sheetname "")
			)
			(fill
				(thermal_gap 0.5)
				(thermal_bridge_width 0.5)
				(island_removal_mode 0)
			)
			(polygon
				(pts
					(xy 182.118 -146.431) (xy 181.61 -146.431) (xy 181.61 -146.05) (xy 182.118 -146.05)
				)
			)
		)
		(zone
			(layer "B.Cu")
			(hatch none 0.5)
			(connect_pads
				(clearance 0)
			)
			(min_thickness 0.25)
			(keepout
				(tracks allowed)
				(vias not_allowed)
				(pads allowed)
				(copperpour not_allowed)
				(footprints allowed)
			)
			(placement
				(enabled no)
				(sheetname "")
			)
			(fill
				(thermal_gap 0.5)
				(thermal_bridge_width 0.5)
				(island_removal_mode 0)
			)
			(polygon
				(pts
					(xy 182.118 -146.431) (xy 181.61 -146.431) (xy 181.61 -146.05) (xy 182.118 -146.05)
				)
			)
		)
	)
	(footprint ""
		(layer "B.Cu")
		(at 2.54 -59.944 -90)
		(property "Reference" "C9R6"
			(at 0 0 90)
			(layer "B.SilkS")
			(hide yes)
			(effects
				(font
					(size 1.27 1.27)
				)
				(justify mirror)
			)
		)
		(property "Value" ""
			(at 0 0 90)
			(layer "B.Fab")
			(effects
				(font
					(size 1.27 1.27)
				)
				(justify mirror)
			)
		)
		(duplicate_pad_numbers_are_jumpers no)
		(fp_rect
			(start 0.3048 -0.1016)
			(end -0.3048 0.9906)
			(stroke
				(width 0)
				(type default)
			)
			(fill no)
			(layer "B.CrtYd")
		)
		(fp_line
			(start -0.3048 0.9906)
			(end -0.3048 -0.1016)
			(stroke
				(width 0.1)
				(type default)
			)
			(layer "B.Fab")
		)
		(fp_line
			(start 0.3048 0.9906)
			(end -0.3048 0.9906)
			(stroke
				(width 0.1)
				(type default)
			)
			(layer "B.Fab")
		)
		(fp_line
			(start -0.3048 -0.1016)
			(end 0.3048 -0.1016)
			(stroke
				(width 0.1)
				(type default)
			)
			(layer "B.Fab")
		)
		(fp_line
			(start 0.3048 -0.1016)
			(end 0.3048 0.9906)
			(stroke
				(width 0.1)
				(type default)
			)
			(layer "B.Fab")
		)
		(pad "1" smd rect
			(at 0 0 90)
			(size 0.508 0.508)
			(layers "B.Cu" "B.Mask" "B.Paste")
			(net "P12V_PSU")
		)
		(pad "2" smd rect
			(at 0 0.889 90)
			(size 0.508 0.508)
			(layers "B.Cu" "B.Mask" "B.Paste")
			(net "GND")
		)
		(zone
			(layer "B.Cu")
			(hatch none 0.5)
			(connect_pads
				(clearance 0)
			)
			(min_thickness 0.25)
			(keepout
				(tracks allowed)
				(vias not_allowed)
				(pads allowed)
				(copperpour not_allowed)
				(footprints allowed)
			)
			(placement
				(enabled no)
				(sheetname "")
			)
			(fill
				(thermal_gap 0.5)
				(thermal_bridge_width 0.5)
				(island_removal_mode 0)
			)
			(polygon
				(pts
					(xy 2.286 -59.69) (xy 2.286 -60.198) (xy 1.905 -60.198) (xy 1.905 -59.69)
				)
			)
		)
		(zone
			(layer "B.Cu")
			(hatch none 0.5)
			(connect_pads
				(clearance 0)
			)
			(min_thickness 0.25)
			(keepout
				(tracks not_allowed)
				(vias allowed)
				(pads allowed)
				(copperpour not_allowed)
				(footprints allowed)
			)
			(placement
				(enabled no)
				(sheetname "")
			)
			(fill
				(thermal_gap 0.5)
				(thermal_bridge_width 0.5)
				(island_removal_mode 0)
			)
			(polygon
				(pts
					(xy 2.286 -59.69) (xy 2.286 -60.198) (xy 1.905 -60.198) (xy 1.905 -59.69)
				)
			)
		)
	)
	(footprint ""
		(layer "B.Cu")
		(at 99.415854 -79.60614 180)
		(property "Reference" "C8P12"
			(at 0 0 0)
			(layer "B.SilkS")
			(hide yes)
			(effects
				(font
					(size 1.27 1.27)
				)
				(justify mirror)
			)
		)
		(property "Value" ""
			(at 0 0 0)
			(layer "B.Fab")
			(effects
				(font
					(size 1.27 1.27)
				)
				(justify mirror)
			)
		)
		(duplicate_pad_numbers_are_jumpers no)
		(fp_poly
			(pts
				(xy 0.7239 -0.2159) (xy -0.7239 -0.2159) (xy -0.7239 1.9939) (xy 0.7239 1.9939)
			)
			(stroke
				(width 0)
				(type default)
			)
			(fill no)
			(layer "B.CrtYd")
		)
		(fp_line
			(start 0.7239 1.9939)
			(end -0.7239 1.9939)
			(stroke
				(width 0.1)
				(type default)
			)
			(layer "B.Fab")
		)
		(fp_line
			(start 0.7239 -0.2159)
			(end 0.7239 1.9939)
			(stroke
				(width 0.1)
				(type default)
			)
			(layer "B.Fab")
		)
		(fp_line
			(start -0.7239 1.9939)
			(end -0.7239 -0.2159)
			(stroke
				(width 0.1)
				(type default)
			)
			(layer "B.Fab")
		)
		(fp_line
			(start -0.7239 -0.2159)
			(end 0.7239 -0.2159)
			(stroke
				(width 0.1)
				(type default)
			)
			(layer "B.Fab")
		)
		(pad "1" smd rect
			(at 0 0)
			(size 1.27 1.016)
			(layers "B.Cu" "B.Mask" "B.Paste")
			(net "PVCCIN_CPU1")
		)
		(pad "2" smd rect
			(at 0 1.778)
			(size 1.27 1.016)
			(layers "B.Cu" "B.Mask" "B.Paste")
			(net "GND")
		)
		(zone
			(layer "B.Cu")
			(hatch none 0.5)
			(connect_pads
				(clearance 0)
			)
			(min_thickness 0.25)
			(keepout
				(tracks not_allowed)
				(vias allowed)
				(pads allowed)
				(copperpour not_allowed)
				(footprints allowed)
			)
			(placement
				(enabled no)
				(sheetname "")
			)
			(fill
				(thermal_gap 0.5)
				(thermal_bridge_width 0.5)
				(island_removal_mode 0)
			)
			(polygon
				(pts
					(xy 98.780854 -80.11414) (xy 100.050854 -80.11414) (xy 100.050854 -80.87614) (xy 98.780854 -80.87614)
				)
			)
		)
	)
)
